# S9S_MB_2U (Grand Teton) — schematic netlist excerpt (pin names and nets, part order shuffled) for the footprints in the layout excerpt that follows; sources: Cadence DE-HDL packaged netlist, KiCad conversion of 03242023_DA0F0TMBIJ0_F0T_Motherboard_J_brd_V01_OCP.brd

C2443  Q_CAP  10UF 6.3V 20% X6S  pkg C0402  page 278 : A = PVNN_TERM_CPU0 ; B = GND
C846  Q_CAP_DIFFBUS  DIFF BUS_0.22UF 6.3V 20% X6S  pkg C0201  page 174 : \1\ = P5E_CPU0_PE1_TX_C_DN<11> ; \2\ = P5E_CPU0_PE1_TX_DN<11>
C610  Q_CAP  1UF 25V 10% X6S  pkg C0402  page 185 : A = RST_SRTCRST_N ; B = GND

(kicad_pcb
	(version 20260206)
	(generator "pcbnew")
	(generator_version "10.0")
	(general
		(thickness 1.6)
		(legacy_teardrops no)
	)
	(paper "A4")
	(title_block
		(title "03242023_DA0F0TMBIJ0_F0T_Motherboard_J_brd_V01_OCP.brd")
		(comment 1 "Grand Teton / footprints 928-930 of 6105")
	)
	(layers
		(0 "F.Cu" signal "TOP")
		(4 "In1.Cu" signal "GND")
		(6 "In2.Cu" signal "IN1")
		(8 "In3.Cu" signal "GND1")
		(10 "In4.Cu" signal "IN2")
		(12 "In5.Cu" signal "GND2")
		(14 "In6.Cu" signal "IN3")
		(16 "In7.Cu" signal "GND3")
		(18 "In8.Cu" signal "VCC")
		(20 "In9.Cu" signal "VCC1")
		(22 "In10.Cu" signal "GND4")
		(24 "In11.Cu" signal "IN4")
		(26 "In12.Cu" signal "GND5")
		(28 "In13.Cu" signal "IN5")
		(30 "In14.Cu" signal "GND6")
		(32 "In15.Cu" signal "IN6")
		(34 "In16.Cu" signal "GND7")
		(2 "B.Cu" signal "BOTTOM")
		(9 "F.Adhes" user "F.Adhesive")
		(11 "B.Adhes" user "B.Adhesive")
		(13 "F.Paste" user "Package Geometry/Pastemask Top")
		(15 "B.Paste" user "Package Geometry/Pastemask Bottom")
		(5 "F.SilkS" user "Ref Des/Silkscreen Top")
		(7 "B.SilkS" user "Ref Des/Silkscreen Bottom")
		(1 "F.Mask" user "Board Geometry/Soldermask Top")
		(3 "B.Mask" user "Board Geometry/Soldermask Bottom")
		(17 "Dwgs.User" user "User.Drawings")
		(19 "Cmts.User" user "User.Comments")
		(21 "Eco1.User" user "User.Eco1")
		(23 "Eco2.User" user "User.Eco2")
		(25 "Edge.Cuts" user "Board Geometry/Outline")
		(27 "Margin" user)
		(31 "F.CrtYd" user "Package Geometry/Place Bound Top")
		(29 "B.CrtYd" user "Package Geometry/Place Bound Bottom")
		(35 "F.Fab" user "Ref Des/Assembly Top")
		(33 "B.Fab" user "Ref Des/Assembly Bottom")
	)
	(footprint ""
		(layer "F.Cu")
		(at 325.193914 -26.143712 180)
		(property "Reference" "C610"
			(at 0 0 180)
			(layer "F.SilkS")
			(hide yes)
			(effects
				(font
					(size 1.27 1.27)
				)
			)
		)
		(property "Value" ""
			(at 0 0 180)
			(layer "F.Fab")
			(effects
				(font
					(size 1.27 1.27)
				)
			)
		)
		(duplicate_pad_numbers_are_jumpers no)
		(fp_line
			(start 0.7874 0.4064)
			(end -0.7874 0.4064)
			(stroke
				(width 0.1524)
				(type default)
			)
			(layer "F.SilkS")
		)
		(fp_line
			(start 0.7874 -0.4064)
			(end 0.7874 0.4064)
			(stroke
				(width 0.1524)
				(type default)
			)
			(layer "F.SilkS")
		)
		(fp_line
			(start -0.7874 0.4064)
			(end -0.7874 -0.4064)
			(stroke
				(width 0.1524)
				(type default)
			)
			(layer "F.SilkS")
		)
		(fp_line
			(start -0.7874 -0.4064)
			(end 0.7874 -0.4064)
			(stroke
				(width 0.1524)
				(type default)
			)
			(layer "F.SilkS")
		)
		(fp_line
			(start 0.67945 0.3048)
			(end 0.120396 0.3048)
			(stroke
				(width 0.1)
				(type default)
			)
			(layer "F.Fab")
		)
		(fp_line
			(start 0.67945 -0.3048)
			(end 0.67945 0.3048)
			(stroke
				(width 0.1)
				(type default)
			)
			(layer "F.Fab")
		)
		(fp_line
			(start 0.12065 -0.2794)
			(end 0.12065 -0.3048)
			(stroke
				(width 0.1)
				(type default)
			)
			(layer "F.Fab")
		)
		(fp_line
			(start 0.12065 -0.3048)
			(end 0.67945 -0.3048)
			(stroke
				(width 0.1)
				(type default)
			)
			(layer "F.Fab")
		)
		(fp_line
			(start 0.120396 0.3048)
			(end 0.120396 0.2794)
			(stroke
				(width 0.1)
				(type default)
			)
			(layer "F.Fab")
		)
		(fp_line
			(start 0.120396 0.2794)
			(end -0.12065 0.2794)
			(stroke
				(width 0.1)
				(type default)
			)
			(layer "F.Fab")
		)
		(fp_line
			(start -0.12065 0.3048)
			(end -0.67945 0.3048)
			(stroke
				(width 0.1)
				(type default)
			)
			(layer "F.Fab")
		)
		(fp_line
			(start -0.12065 0.2794)
			(end -0.12065 0.3048)
			(stroke
				(width 0.1)
				(type default)
			)
			(layer "F.Fab")
		)
		(fp_line
			(start -0.12065 -0.2794)
			(end 0.12065 -0.2794)
			(stroke
				(width 0.1)
				(type default)
			)
			(layer "F.Fab")
		)
		(fp_line
			(start -0.12065 -0.305054)
			(end -0.12065 -0.2794)
			(stroke
				(width 0.1)
				(type default)
			)
			(layer "F.Fab")
		)
		(fp_line
			(start -0.67945 0.3048)
			(end -0.67945 -0.305054)
			(stroke
				(width 0.1)
				(type default)
			)
			(layer "F.Fab")
		)
		(fp_line
			(start -0.67945 -0.305054)
			(end -0.12065 -0.305054)
			(stroke
				(width 0.1)
				(type default)
			)
			(layer "F.Fab")
		)
		(pad "1" smd circle
			(at -0.40005 0 180)
			(size 0 0)
			(layers "F.Cu" "F.Mask" "F.Paste")
			(net "RST_SRTCRST_N")
		)
		(pad "2" smd circle
			(at 0.40005 0 180)
			(size 0 0)
			(layers "F.Cu" "F.Mask" "F.Paste")
			(net "GND")
		)
	)
	(footprint ""
		(layer "F.Cu")
		(at 441.099194 -125.035818 90)
		(property "Reference" "C2443"
			(at 0 0 90)
			(layer "F.SilkS")
			(hide yes)
			(effects
				(font
					(size 1.27 1.27)
				)
			)
		)
		(property "Value" ""
			(at 0 0 90)
			(layer "F.Fab")
			(effects
				(font
					(size 1.27 1.27)
				)
			)
		)
		(duplicate_pad_numbers_are_jumpers no)
		(fp_line
			(start 0.7874 -0.4064)
			(end 0.7874 0.4064)
			(stroke
				(width 0.1524)
				(type default)
			)
			(layer "F.SilkS")
		)
		(fp_line
			(start -0.7874 -0.4064)
			(end 0.7874 -0.4064)
			(stroke
				(width 0.1524)
				(type default)
			)
			(layer "F.SilkS")
		)
		(fp_line
			(start 0.7874 0.4064)
			(end -0.7874 0.4064)
			(stroke
				(width 0.1524)
				(type default)
			)
			(layer "F.SilkS")
		)
		(fp_line
			(start -0.7874 0.4064)
			(end -0.7874 -0.4064)
			(stroke
				(width 0.1524)
				(type default)
			)
			(layer "F.SilkS")
		)
		(fp_line
			(start -0.12065 -0.305054)
			(end -0.12065 -0.2794)
			(stroke
				(width 0.1)
				(type default)
			)
			(layer "F.Fab")
		)
		(fp_line
			(start -0.67945 -0.305054)
			(end -0.12065 -0.305054)
			(stroke
				(width 0.1)
				(type default)
			)
			(layer "F.Fab")
		)
		(fp_line
			(start 0.67945 -0.3048)
			(end 0.67945 0.3048)
			(stroke
				(width 0.1)
				(type default)
			)
			(layer "F.Fab")
		)
		(fp_line
			(start 0.12065 -0.3048)
			(end 0.67945 -0.3048)
			(stroke
				(width 0.1)
				(type default)
			)
			(layer "F.Fab")
		)
		(fp_line
			(start 0.12065 -0.2794)
			(end 0.12065 -0.3048)
			(stroke
				(width 0.1)
				(type default)
			)
			(layer "F.Fab")
		)
		(fp_line
			(start -0.12065 -0.2794)
			(end 0.12065 -0.2794)
			(stroke
				(width 0.1)
				(type default)
			)
			(layer "F.Fab")
		)
		(fp_line
			(start 0.120396 0.2794)
			(end -0.12065 0.2794)
			(stroke
				(width 0.1)
				(type default)
			)
			(layer "F.Fab")
		)
		(fp_line
			(start -0.12065 0.2794)
			(end -0.12065 0.3048)
			(stroke
				(width 0.1)
				(type default)
			)
			(layer "F.Fab")
		)
		(fp_line
			(start 0.67945 0.3048)
			(end 0.120396 0.3048)
			(stroke
				(width 0.1)
				(type default)
			)
			(layer "F.Fab")
		)
		(fp_line
			(start 0.120396 0.3048)
			(end 0.120396 0.2794)
			(stroke
				(width 0.1)
				(type default)
			)
			(layer "F.Fab")
		)
		(fp_line
			(start -0.12065 0.3048)
			(end -0.67945 0.3048)
			(stroke
				(width 0.1)
				(type default)
			)
			(layer "F.Fab")
		)
		(fp_line
			(start -0.67945 0.3048)
			(end -0.67945 -0.305054)
			(stroke
				(width 0.1)
				(type default)
			)
			(layer "F.Fab")
		)
		(pad "1" smd circle
			(at -0.40005 0 90)
			(size 0 0)
			(layers "F.Cu" "F.Mask" "F.Paste")
			(net "PVNN_TERM_CPU0")
		)
		(pad "2" smd circle
			(at 0.40005 0 90)
			(size 0 0)
			(layers "F.Cu" "F.Mask" "F.Paste")
			(net "GND")
		)
	)
	(footprint ""
		(layer "F.Cu")
		(at 402.106384 -16.088614 90)
		(property "Reference" "C846"
			(at 0 0 90)
			(layer "F.SilkS")
			(hide yes)
			(effects
				(font
					(size 1.27 1.27)
				)
			)
		)
		(property "Value" ""
			(at 0 0 90)
			(layer "F.Fab")
			(effects
				(font
					(size 1.27 1.27)
				)
			)
		)
		(duplicate_pad_numbers_are_jumpers no)
		(fp_line
			(start 0.299974 -0.150114)
			(end 0.299974 0.150114)
			(stroke
				(width 0.1)
				(type default)
			)
			(layer "F.Fab")
		)
		(fp_line
			(start -0.299974 -0.150114)
			(end 0.299974 -0.150114)
			(stroke
				(width 0.1)
				(type default)
			)
			(layer "F.Fab")
		)
		(fp_line
			(start 0.299974 0.150114)
			(end -0.299974 0.150114)
			(stroke
				(width 0.1)
				(type default)
			)
			(layer "F.Fab")
		)
		(fp_line
			(start -0.299974 0.150114)
			(end -0.299974 -0.150114)
			(stroke
				(width 0.1)
				(type default)
			)
			(layer "F.Fab")
		)
		(pad "1" smd rect
			(at -0.2667 0 90)
			(size 0.3048 0.381)
			(layers "F.Cu" "F.Mask" "F.Paste")
			(net "P5E_CPU0_PE1_TX_C_DN<11>")
		)
		(pad "2" smd rect
			(at 0.2667 0 90)
			(size 0.3048 0.381)
			(layers "F.Cu" "F.Mask" "F.Paste")
			(net "P5E_CPU0_PE1_TX_DN<11>")
		)
	)
)
